# S9S_MB_2U (Grand Teton) — schematic netlist excerpt (pin names and nets, part order shuffled) for the footprints in the layout excerpt that follows; sources: Cadence DE-HDL packaged netlist, KiCad conversion of 03242023_DA0F0TMBIJ0_F0T_Motherboard_J_brd_V01_OCP.brd

PC190  Q_CAP  1UF 25V 10% X6S  pkg C0402  page 162 : A = P3V3_OCP_VCC_2 ; B = GND
R2820  Q_RES  4.7K 5% EMPTY  pkg 0402LF  page 151 : A = P3V3_AUX ; B = BMC_MONITER_BUF_R

(kicad_pcb
	(version 20260206)
	(generator "pcbnew")
	(generator_version "10.0")
	(general
		(thickness 1.6)
		(legacy_teardrops no)
	)
	(paper "A4")
	(title_block
		(title "03242023_DA0F0TMBIJ0_F0T_Motherboard_J_brd_V01_OCP.brd")
		(comment 1 "Grand Teton / footprints 3856-3857 of 6105")
	)
	(layers
		(0 "F.Cu" signal "TOP")
		(4 "In1.Cu" signal "GND")
		(6 "In2.Cu" signal "IN1")
		(8 "In3.Cu" signal "GND1")
		(10 "In4.Cu" signal "IN2")
		(12 "In5.Cu" signal "GND2")
		(14 "In6.Cu" signal "IN3")
		(16 "In7.Cu" signal "GND3")
		(18 "In8.Cu" signal "VCC")
		(20 "In9.Cu" signal "VCC1")
		(22 "In10.Cu" signal "GND4")
		(24 "In11.Cu" signal "IN4")
		(26 "In12.Cu" signal "GND5")
		(28 "In13.Cu" signal "IN5")
		(30 "In14.Cu" signal "GND6")
		(32 "In15.Cu" signal "IN6")
		(34 "In16.Cu" signal "GND7")
		(2 "B.Cu" signal "BOTTOM")
		(9 "F.Adhes" user "F.Adhesive")
		(11 "B.Adhes" user "B.Adhesive")
		(13 "F.Paste" user "Package Geometry/Pastemask Top")
		(15 "B.Paste" user "Package Geometry/Pastemask Bottom")
		(5 "F.SilkS" user "Ref Des/Silkscreen Top")
		(7 "B.SilkS" user "Ref Des/Silkscreen Bottom")
		(1 "F.Mask" user "Board Geometry/Soldermask Top")
		(3 "B.Mask" user "Board Geometry/Soldermask Bottom")
		(17 "Dwgs.User" user "User.Drawings")
		(19 "Cmts.User" user "User.Comments")
		(21 "Eco1.User" user "User.Eco1")
		(23 "Eco2.User" user "User.Eco2")
		(25 "Edge.Cuts" user "Board Geometry/Outline")
		(27 "Margin" user)
		(31 "F.CrtYd" user "Package Geometry/Place Bound Top")
		(29 "B.CrtYd" user "Package Geometry/Place Bound Bottom")
		(35 "F.Fab" user "Ref Des/Assembly Top")
		(33 "B.Fab" user "Ref Des/Assembly Bottom")
	)
	(footprint ""
		(layer "F.Cu")
		(at 85.915246 -57.279286 90)
		(property "Reference" "PC190"
			(at 0 0 90)
			(layer "F.SilkS")
			(hide yes)
			(effects
				(font
					(size 1.27 1.27)
				)
			)
		)
		(property "Value" ""
			(at 0 0 90)
			(layer "F.Fab")
			(effects
				(font
					(size 1.27 1.27)
				)
			)
		)
		(duplicate_pad_numbers_are_jumpers no)
		(fp_line
			(start 0.7874 -0.4064)
			(end 0.7874 0.4064)
			(stroke
				(width 0.1524)
				(type default)
			)
			(layer "F.SilkS")
		)
		(fp_line
			(start -0.7874 -0.4064)
			(end 0.7874 -0.4064)
			(stroke
				(width 0.1524)
				(type default)
			)
			(layer "F.SilkS")
		)
		(fp_line
			(start 0.7874 0.4064)
			(end -0.7874 0.4064)
			(stroke
				(width 0.1524)
				(type default)
			)
			(layer "F.SilkS")
		)
		(fp_line
			(start -0.7874 0.4064)
			(end -0.7874 -0.4064)
			(stroke
				(width 0.1524)
				(type default)
			)
			(layer "F.SilkS")
		)
		(fp_line
			(start -0.12065 -0.305054)
			(end -0.12065 -0.2794)
			(stroke
				(width 0.1)
				(type default)
			)
			(layer "F.Fab")
		)
		(fp_line
			(start -0.67945 -0.305054)
			(end -0.12065 -0.305054)
			(stroke
				(width 0.1)
				(type default)
			)
			(layer "F.Fab")
		)
		(fp_line
			(start 0.67945 -0.3048)
			(end 0.67945 0.3048)
			(stroke
				(width 0.1)
				(type default)
			)
			(layer "F.Fab")
		)
		(fp_line
			(start 0.12065 -0.3048)
			(end 0.67945 -0.3048)
			(stroke
				(width 0.1)
				(type default)
			)
			(layer "F.Fab")
		)
		(fp_line
			(start 0.12065 -0.2794)
			(end 0.12065 -0.3048)
			(stroke
				(width 0.1)
				(type default)
			)
			(layer "F.Fab")
		)
		(fp_line
			(start -0.12065 -0.2794)
			(end 0.12065 -0.2794)
			(stroke
				(width 0.1)
				(type default)
			)
			(layer "F.Fab")
		)
		(fp_line
			(start 0.120396 0.2794)
			(end -0.12065 0.2794)
			(stroke
				(width 0.1)
				(type default)
			)
			(layer "F.Fab")
		)
		(fp_line
			(start -0.12065 0.2794)
			(end -0.12065 0.3048)
			(stroke
				(width 0.1)
				(type default)
			)
			(layer "F.Fab")
		)
		(fp_line
			(start 0.67945 0.3048)
			(end 0.120396 0.3048)
			(stroke
				(width 0.1)
				(type default)
			)
			(layer "F.Fab")
		)
		(fp_line
			(start 0.120396 0.3048)
			(end 0.120396 0.2794)
			(stroke
				(width 0.1)
				(type default)
			)
			(layer "F.Fab")
		)
		(fp_line
			(start -0.12065 0.3048)
			(end -0.67945 0.3048)
			(stroke
				(width 0.1)
				(type default)
			)
			(layer "F.Fab")
		)
		(fp_line
			(start -0.67945 0.3048)
			(end -0.67945 -0.305054)
			(stroke
				(width 0.1)
				(type default)
			)
			(layer "F.Fab")
		)
		(pad "1" smd circle
			(at -0.40005 0 90)
			(size 0 0)
			(layers "F.Cu" "F.Mask" "F.Paste")
			(net "P3V3_OCP_VCC_2")
		)
		(pad "2" smd circle
			(at 0.40005 0 90)
			(size 0 0)
			(layers "F.Cu" "F.Mask" "F.Paste")
			(net "GND")
		)
	)
	(footprint ""
		(layer "F.Cu")
		(at 176.17948 -426.430948 180)
		(property "Reference" "R2820"
			(at 0 0 180)
			(layer "F.SilkS")
			(hide yes)
			(effects
				(font
					(size 1.27 1.27)
				)
			)
		)
		(property "Value" ""
			(at 0 0 180)
			(layer "F.Fab")
			(effects
				(font
					(size 1.27 1.27)
				)
			)
		)
		(duplicate_pad_numbers_are_jumpers no)
		(fp_line
			(start 0.7874 0.4064)
			(end -0.7874 0.4064)
			(stroke
				(width 0.1524)
				(type default)
			)
			(layer "F.SilkS")
		)
		(fp_line
			(start 0.7874 -0.4064)
			(end 0.7874 0.4064)
			(stroke
				(width 0.1524)
				(type default)
			)
			(layer "F.SilkS")
		)
		(fp_line
			(start -0.7874 0.4064)
			(end -0.7874 -0.4064)
			(stroke
				(width 0.1524)
				(type default)
			)
			(layer "F.SilkS")
		)
		(fp_line
			(start -0.7874 -0.4064)
			(end 0.7874 -0.4064)
			(stroke
				(width 0.1524)
				(type default)
			)
			(layer "F.SilkS")
		)
		(fp_line
			(start 0.67945 0.3048)
			(end 0.120396 0.3048)
			(stroke
				(width 0.1)
				(type default)
			)
			(layer "F.Fab")
		)
		(fp_line
			(start 0.67945 -0.3048)
			(end 0.67945 0.3048)
			(stroke
				(width 0.1)
				(type default)
			)
			(layer "F.Fab")
		)
		(fp_line
			(start 0.12065 -0.2794)
			(end 0.12065 -0.3048)
			(stroke
				(width 0.1)
				(type default)
			)
			(layer "F.Fab")
		)
		(fp_line
			(start 0.12065 -0.3048)
			(end 0.67945 -0.3048)
			(stroke
				(width 0.1)
				(type default)
			)
			(layer "F.Fab")
		)
		(fp_line
			(start 0.120396 0.3048)
			(end 0.120396 0.2794)
			(stroke
				(width 0.1)
				(type default)
			)
			(layer "F.Fab")
		)
		(fp_line
			(start 0.120396 0.2794)
			(end -0.12065 0.2794)
			(stroke
				(width 0.1)
				(type default)
			)
			(layer "F.Fab")
		)
		(fp_line
			(start -0.12065 0.3048)
			(end -0.67945 0.3048)
			(stroke
				(width 0.1)
				(type default)
			)
			(layer "F.Fab")
		)
		(fp_line
			(start -0.12065 0.2794)
			(end -0.12065 0.3048)
			(stroke
				(width 0.1)
				(type default)
			)
			(layer "F.Fab")
		)
		(fp_line
			(start -0.12065 -0.2794)
			(end 0.12065 -0.2794)
			(stroke
				(width 0.1)
				(type default)
			)
			(layer "F.Fab")
		)
		(fp_line
			(start -0.12065 -0.305054)
			(end -0.12065 -0.2794)
			(stroke
				(width 0.1)
				(type default)
			)
			(layer "F.Fab")
		)
		(fp_line
			(start -0.67945 0.3048)
			(end -0.67945 -0.305054)
			(stroke
				(width 0.1)
				(type default)
			)
			(layer "F.Fab")
		)
		(fp_line
			(start -0.67945 -0.305054)
			(end -0.12065 -0.305054)
			(stroke
				(width 0.1)
				(type default)
			)
			(layer "F.Fab")
		)
		(pad "1" smd circle
			(at -0.40005 0 180)
			(size 0 0)
			(layers "F.Cu" "F.Mask" "F.Paste")
			(net "P3V3_AUX")
		)
		(pad "2" smd circle
			(at 0.40005 0 180)
			(size 0 0)
			(layers "F.Cu" "F.Mask" "F.Paste")
			(net "BMC_MONITER_BUF_R")
		)
	)
)
